(kicad_pcb
	(version 20260206)
	(generator "pcbnew")
	(generator_version "10.0")
	(general
		(thickness 1.6)
		(legacy_teardrops no)
	)
	(paper "A4")
	(title_block
		(title "04192023_DAF0TMB3IC0_F0TG_MB_C_brd_V02_OCP.brd")
		(comment 1 "Grand Teton / footprints 6713-6719 of 8354")
	)
	(layers
		(0 "F.Cu" signal "TOP")
		(4 "In1.Cu" signal "GND")
		(6 "In2.Cu" signal "IN1")
		(8 "In3.Cu" signal "GND1")
		(10 "In4.Cu" signal "IN2")
		(12 "In5.Cu" signal "GND2")
		(14 "In6.Cu" signal "IN3")
		(16 "In7.Cu" signal "GND3")
		(18 "In8.Cu" signal "VCC")
		(20 "In9.Cu" signal "VCC1")
		(22 "In10.Cu" signal "GND4")
		(24 "In11.Cu" signal "IN4")
		(26 "In12.Cu" signal "GND5")
		(28 "In13.Cu" signal "IN5")
		(30 "In14.Cu" signal "GND6")
		(32 "In15.Cu" signal "IN6")
		(34 "In16.Cu" signal "GND7")
		(2 "B.Cu" signal "BOTTOM")
		(9 "F.Adhes" user "F.Adhesive")
		(11 "B.Adhes" user "B.Adhesive")
		(13 "F.Paste" user "Package Geometry/Pastemask Top")
		(15 "B.Paste" user "Package Geometry/Pastemask Bottom")
		(5 "F.SilkS" user "Ref Des/Silkscreen Top")
		(7 "B.SilkS" user "Ref Des/Silkscreen Bottom")
		(1 "F.Mask" user "Board Geometry/Soldermask Top")
		(3 "B.Mask" user "Board Geometry/Soldermask Bottom")
		(17 "Dwgs.User" user "User.Drawings")
		(19 "Cmts.User" user "User.Comments")
		(21 "Eco1.User" user "User.Eco1")
		(23 "Eco2.User" user "User.Eco2")
		(25 "Edge.Cuts" user "Board Geometry/Outline")
		(27 "Margin" user)
		(31 "F.CrtYd" user "Package Geometry/Place Bound Top")
		(29 "B.CrtYd" user "Package Geometry/Place Bound Bottom")
		(35 "F.Fab" user "Ref Des/Assembly Top")
		(33 "B.Fab" user "Ref Des/Assembly Bottom")
	)
	(footprint ""
		(layer "B.Cu")
		(at 171.2087 -111.183928)
		(property "Reference" "R171"
			(at 0 0 0)
			(layer "B.SilkS")
			(hide yes)
			(effects
				(font
					(size 1.27 1.27)
				)
				(justify mirror)
			)
		)
		(property "Value" ""
			(at 0 0 0)
			(layer "B.Fab")
			(effects
				(font
					(size 1.27 1.27)
				)
				(justify mirror)
			)
		)
		(duplicate_pad_numbers_are_jumpers no)
		(fp_line
			(start -0.7874 -0.4064)
			(end -0.7874 0.4064)
			(stroke
				(width 0.1524)
				(type default)
			)
			(layer "B.SilkS")
		)
		(fp_line
			(start -0.7874 0.4064)
			(end 0.7874 0.4064)
			(stroke
				(width 0.1524)
				(type default)
			)
			(layer "B.SilkS")
		)
		(fp_line
			(start 0.7874 -0.4064)
			(end -0.7874 -0.4064)
			(stroke
				(width 0.1524)
				(type default)
			)
			(layer "B.SilkS")
		)
		(fp_line
			(start 0.7874 0.4064)
			(end 0.7874 -0.4064)
			(stroke
				(width 0.1524)
				(type default)
			)
			(layer "B.SilkS")
		)
		(fp_line
			(start -0.67945 -0.3048)
			(end -0.67945 0.3048)
			(stroke
				(width 0.1)
				(type default)
			)
			(layer "B.Fab")
		)
		(fp_line
			(start -0.67945 0.3048)
			(end -0.120396 0.3048)
			(stroke
				(width 0.1)
				(type default)
			)
			(layer "B.Fab")
		)
		(fp_line
			(start -0.12065 -0.3048)
			(end -0.67945 -0.3048)
			(stroke
				(width 0.1)
				(type default)
			)
			(layer "B.Fab")
		)
		(fp_line
			(start -0.12065 -0.2794)
			(end -0.12065 -0.3048)
			(stroke
				(width 0.1)
				(type default)
			)
			(layer "B.Fab")
		)
		(fp_line
			(start -0.120396 0.2794)
			(end 0.12065 0.2794)
			(stroke
				(width 0.1)
				(type default)
			)
			(layer "B.Fab")
		)
		(fp_line
			(start -0.120396 0.3048)
			(end -0.120396 0.2794)
			(stroke
				(width 0.1)
				(type default)
			)
			(layer "B.Fab")
		)
		(fp_line
			(start 0.12065 -0.305054)
			(end 0.12065 -0.2794)
			(stroke
				(width 0.1)
				(type default)
			)
			(layer "B.Fab")
		)
		(fp_line
			(start 0.12065 -0.2794)
			(end -0.12065 -0.2794)
			(stroke
				(width 0.1)
				(type default)
			)
			(layer "B.Fab")
		)
		(fp_line
			(start 0.12065 0.2794)
			(end 0.12065 0.3048)
			(stroke
				(width 0.1)
				(type default)
			)
			(layer "B.Fab")
		)
		(fp_line
			(start 0.12065 0.3048)
			(end 0.67945 0.3048)
			(stroke
				(width 0.1)
				(type default)
			)
			(layer "B.Fab")
		)
		(fp_line
			(start 0.67945 -0.305054)
			(end 0.12065 -0.305054)
			(stroke
				(width 0.1)
				(type default)
			)
			(layer "B.Fab")
		)
		(fp_line
			(start 0.67945 0.3048)
			(end 0.67945 -0.305054)
			(stroke
				(width 0.1)
				(type default)
			)
			(layer "B.Fab")
		)
		(pad "1" smd circle
			(at 0.40005 0 180)
			(size 0 0)
			(layers "B.Cu" "B.Mask" "B.Paste")
			(net "FM_I3C_CPU1_MUX1_OE_R_N")
		)
		(pad "2" smd circle
			(at -0.40005 0 180)
			(size 0 0)
			(layers "B.Cu" "B.Mask" "B.Paste")
			(net "FM_I3C_CPU1_MUX1_OE_N")
		)
	)
	(footprint ""
		(layer "B.Cu")
		(at 346.545408 -254.95631)
		(property "Reference" "C2520"
			(at 0 0 0)
			(layer "B.SilkS")
			(hide yes)
			(effects
				(font
					(size 1.27 1.27)
				)
				(justify mirror)
			)
		)
		(property "Value" ""
			(at 0 0 0)
			(layer "B.Fab")
			(effects
				(font
					(size 1.27 1.27)
				)
				(justify mirror)
			)
		)
		(duplicate_pad_numbers_are_jumpers no)
		(fp_line
			(start -0.7874 -0.4064)
			(end -0.7874 0.4064)
			(stroke
				(width 0.1524)
				(type default)
			)
			(layer "B.SilkS")
		)
		(fp_line
			(start -0.7874 0.4064)
			(end 0.7874 0.4064)
			(stroke
				(width 0.1524)
				(type default)
			)
			(layer "B.SilkS")
		)
		(fp_line
			(start 0.7874 -0.4064)
			(end -0.7874 -0.4064)
			(stroke
				(width 0.1524)
				(type default)
			)
			(layer "B.SilkS")
		)
		(fp_line
			(start 0.7874 0.4064)
			(end 0.7874 -0.4064)
			(stroke
				(width 0.1524)
				(type default)
			)
			(layer "B.SilkS")
		)
		(fp_line
			(start -0.67945 -0.3048)
			(end -0.67945 0.3048)
			(stroke
				(width 0.1)
				(type default)
			)
			(layer "B.Fab")
		)
		(fp_line
			(start -0.67945 0.3048)
			(end -0.120396 0.3048)
			(stroke
				(width 0.1)
				(type default)
			)
			(layer "B.Fab")
		)
		(fp_line
			(start -0.12065 -0.3048)
			(end -0.67945 -0.3048)
			(stroke
				(width 0.1)
				(type default)
			)
			(layer "B.Fab")
		)
		(fp_line
			(start -0.12065 -0.2794)
			(end -0.12065 -0.3048)
			(stroke
				(width 0.1)
				(type default)
			)
			(layer "B.Fab")
		)
		(fp_line
			(start -0.120396 0.2794)
			(end 0.12065 0.2794)
			(stroke
				(width 0.1)
				(type default)
			)
			(layer "B.Fab")
		)
		(fp_line
			(start -0.120396 0.3048)
			(end -0.120396 0.2794)
			(stroke
				(width 0.1)
				(type default)
			)
			(layer "B.Fab")
		)
		(fp_line
			(start 0.12065 -0.305054)
			(end 0.12065 -0.2794)
			(stroke
				(width 0.1)
				(type default)
			)
			(layer "B.Fab")
		)
		(fp_line
			(start 0.12065 -0.2794)
			(end -0.12065 -0.2794)
			(stroke
				(width 0.1)
				(type default)
			)
			(layer "B.Fab")
		)
		(fp_line
			(start 0.12065 0.2794)
			(end 0.12065 0.3048)
			(stroke
				(width 0.1)
				(type default)
			)
			(layer "B.Fab")
		)
		(fp_line
			(start 0.12065 0.3048)
			(end 0.67945 0.3048)
			(stroke
				(width 0.1)
				(type default)
			)
			(layer "B.Fab")
		)
		(fp_line
			(start 0.67945 -0.305054)
			(end 0.12065 -0.305054)
			(stroke
				(width 0.1)
				(type default)
			)
			(layer "B.Fab")
		)
		(fp_line
			(start 0.67945 0.3048)
			(end 0.67945 -0.305054)
			(stroke
				(width 0.1)
				(type default)
			)
			(layer "B.Fab")
		)
		(pad "1" smd circle
			(at 0.40005 0 180)
			(size 0 0)
			(layers "B.Cu" "B.Mask" "B.Paste")
			(net "PVDD18_S5_P0")
		)
		(pad "2" smd circle
			(at -0.40005 0 180)
			(size 0 0)
			(layers "B.Cu" "B.Mask" "B.Paste")
			(net "GND")
		)
	)
	(footprint ""
		(layer "B.Cu")
		(at 116.499386 -248.479564)
		(property "Reference" "C2331"
			(at 0 0 0)
			(layer "B.SilkS")
			(hide yes)
			(effects
				(font
					(size 1.27 1.27)
				)
				(justify mirror)
			)
		)
		(property "Value" ""
			(at 0 0 0)
			(layer "B.Fab")
			(effects
				(font
					(size 1.27 1.27)
				)
				(justify mirror)
			)
		)
		(duplicate_pad_numbers_are_jumpers no)
		(fp_line
			(start -0.7874 -0.4064)
			(end -0.7874 0.4064)
			(stroke
				(width 0.1524)
				(type default)
			)
			(layer "B.SilkS")
		)
		(fp_line
			(start -0.7874 0.4064)
			(end 0.7874 0.4064)
			(stroke
				(width 0.1524)
				(type default)
			)
			(layer "B.SilkS")
		)
		(fp_line
			(start 0.7874 -0.4064)
			(end -0.7874 -0.4064)
			(stroke
				(width 0.1524)
				(type default)
			)
			(layer "B.SilkS")
		)
		(fp_line
			(start 0.7874 0.4064)
			(end 0.7874 -0.4064)
			(stroke
				(width 0.1524)
				(type default)
			)
			(layer "B.SilkS")
		)
		(fp_line
			(start -0.67945 -0.3048)
			(end -0.67945 0.3048)
			(stroke
				(width 0.1)
				(type default)
			)
			(layer "B.Fab")
		)
		(fp_line
			(start -0.67945 0.3048)
			(end -0.120396 0.3048)
			(stroke
				(width 0.1)
				(type default)
			)
			(layer "B.Fab")
		)
		(fp_line
			(start -0.12065 -0.3048)
			(end -0.67945 -0.3048)
			(stroke
				(width 0.1)
				(type default)
			)
			(layer "B.Fab")
		)
		(fp_line
			(start -0.12065 -0.2794)
			(end -0.12065 -0.3048)
			(stroke
				(width 0.1)
				(type default)
			)
			(layer "B.Fab")
		)
		(fp_line
			(start -0.120396 0.2794)
			(end 0.12065 0.2794)
			(stroke
				(width 0.1)
				(type default)
			)
			(layer "B.Fab")
		)
		(fp_line
			(start -0.120396 0.3048)
			(end -0.120396 0.2794)
			(stroke
				(width 0.1)
				(type default)
			)
			(layer "B.Fab")
		)
		(fp_line
			(start 0.12065 -0.305054)
			(end 0.12065 -0.2794)
			(stroke
				(width 0.1)
				(type default)
			)
			(layer "B.Fab")
		)
		(fp_line
			(start 0.12065 -0.2794)
			(end -0.12065 -0.2794)
			(stroke
				(width 0.1)
				(type default)
			)
			(layer "B.Fab")
		)
		(fp_line
			(start 0.12065 0.2794)
			(end 0.12065 0.3048)
			(stroke
				(width 0.1)
				(type default)
			)
			(layer "B.Fab")
		)
		(fp_line
			(start 0.12065 0.3048)
			(end 0.67945 0.3048)
			(stroke
				(width 0.1)
				(type default)
			)
			(layer "B.Fab")
		)
		(fp_line
			(start 0.67945 -0.305054)
			(end 0.12065 -0.305054)
			(stroke
				(width 0.1)
				(type default)
			)
			(layer "B.Fab")
		)
		(fp_line
			(start 0.67945 0.3048)
			(end 0.67945 -0.305054)
			(stroke
				(width 0.1)
				(type default)
			)
			(layer "B.Fab")
		)
		(pad "1" smd circle
			(at 0.40005 0 180)
			(size 0 0)
			(layers "B.Cu" "B.Mask" "B.Paste")
			(net "PVDDCR_CPU0_P1")
		)
		(pad "2" smd circle
			(at -0.40005 0 180)
			(size 0 0)
			(layers "B.Cu" "B.Mask" "B.Paste")
			(net "GND")
		)
	)
	(footprint ""
		(layer "B.Cu")
		(at 108.371386 -267.529564)
		(property "Reference" "C2380"
			(at 0 0 0)
			(layer "B.SilkS")
			(hide yes)
			(effects
				(font
					(size 1.27 1.27)
				)
				(justify mirror)
			)
		)
		(property "Value" ""
			(at 0 0 0)
			(layer "B.Fab")
			(effects
				(font
					(size 1.27 1.27)
				)
				(justify mirror)
			)
		)
		(duplicate_pad_numbers_are_jumpers no)
		(fp_line
			(start -0.7874 -0.4064)
			(end -0.7874 0.4064)
			(stroke
				(width 0.1524)
				(type default)
			)
			(layer "B.SilkS")
		)
		(fp_line
			(start -0.7874 0.4064)
			(end 0.7874 0.4064)
			(stroke
				(width 0.1524)
				(type default)
			)
			(layer "B.SilkS")
		)
		(fp_line
			(start 0.7874 -0.4064)
			(end -0.7874 -0.4064)
			(stroke
				(width 0.1524)
				(type default)
			)
			(layer "B.SilkS")
		)
		(fp_line
			(start 0.7874 0.4064)
			(end 0.7874 -0.4064)
			(stroke
				(width 0.1524)
				(type default)
			)
			(layer "B.SilkS")
		)
		(fp_line
			(start -0.67945 -0.3048)
			(end -0.67945 0.3048)
			(stroke
				(width 0.1)
				(type default)
			)
			(layer "B.Fab")
		)
		(fp_line
			(start -0.67945 0.3048)
			(end -0.120396 0.3048)
			(stroke
				(width 0.1)
				(type default)
			)
			(layer "B.Fab")
		)
		(fp_line
			(start -0.12065 -0.3048)
			(end -0.67945 -0.3048)
			(stroke
				(width 0.1)
				(type default)
			)
			(layer "B.Fab")
		)
		(fp_line
			(start -0.12065 -0.2794)
			(end -0.12065 -0.3048)
			(stroke
				(width 0.1)
				(type default)
			)
			(layer "B.Fab")
		)
		(fp_line
			(start -0.120396 0.2794)
			(end 0.12065 0.2794)
			(stroke
				(width 0.1)
				(type default)
			)
			(layer "B.Fab")
		)
		(fp_line
			(start -0.120396 0.3048)
			(end -0.120396 0.2794)
			(stroke
				(width 0.1)
				(type default)
			)
			(layer "B.Fab")
		)
		(fp_line
			(start 0.12065 -0.305054)
			(end 0.12065 -0.2794)
			(stroke
				(width 0.1)
				(type default)
			)
			(layer "B.Fab")
		)
		(fp_line
			(start 0.12065 -0.2794)
			(end -0.12065 -0.2794)
			(stroke
				(width 0.1)
				(type default)
			)
			(layer "B.Fab")
		)
		(fp_line
			(start 0.12065 0.2794)
			(end 0.12065 0.3048)
			(stroke
				(width 0.1)
				(type default)
			)
			(layer "B.Fab")
		)
		(fp_line
			(start 0.12065 0.3048)
			(end 0.67945 0.3048)
			(stroke
				(width 0.1)
				(type default)
			)
			(layer "B.Fab")
		)
		(fp_line
			(start 0.67945 -0.305054)
			(end 0.12065 -0.305054)
			(stroke
				(width 0.1)
				(type default)
			)
			(layer "B.Fab")
		)
		(fp_line
			(start 0.67945 0.3048)
			(end 0.67945 -0.305054)
			(stroke
				(width 0.1)
				(type default)
			)
			(layer "B.Fab")
		)
		(pad "1" smd circle
			(at 0.40005 0 180)
			(size 0 0)
			(layers "B.Cu" "B.Mask" "B.Paste")
			(net "PVDDCR_CPU1_P1")
		)
		(pad "2" smd circle
			(at -0.40005 0 180)
			(size 0 0)
			(layers "B.Cu" "B.Mask" "B.Paste")
			(net "GND")
		)
	)
	(footprint ""
		(layer "B.Cu")
		(at 363.287056 -177.894996 -90)
		(property "Reference" "PC485_1"
			(at 0 0 90)
			(layer "B.SilkS")
			(hide yes)
			(effects
				(font
					(size 1.27 1.27)
				)
				(justify mirror)
			)
		)
		(property "Value" ""
			(at 0 0 90)
			(layer "B.Fab")
			(effects
				(font
					(size 1.27 1.27)
				)
				(justify mirror)
			)
		)
		(duplicate_pad_numbers_are_jumpers no)
		(fp_line
			(start -1.524 0.762)
			(end 1.524 0.762)
			(stroke
				(width 0.1524)
				(type default)
			)
			(layer "B.SilkS")
		)
		(fp_line
			(start 1.524 0.762)
			(end 1.524 -0.762)
			(stroke
				(width 0.1524)
				(type default)
			)
			(layer "B.SilkS")
		)
		(fp_line
			(start -1.524 -0.762)
			(end -1.524 0.762)
			(stroke
				(width 0.1524)
				(type default)
			)
			(layer "B.SilkS")
		)
		(fp_line
			(start 1.524 -0.762)
			(end -1.524 -0.762)
			(stroke
				(width 0.1524)
				(type default)
			)
			(layer "B.SilkS")
		)
		(fp_line
			(start -1.1049 0.724916)
			(end -1.1049 -0.724916)
			(stroke
				(width 0.1)
				(type default)
			)
			(layer "B.Fab")
		)
		(fp_line
			(start 1.1049 0.724916)
			(end -1.1049 0.724916)
			(stroke
				(width 0.1)
				(type default)
			)
			(layer "B.Fab")
		)
		(fp_line
			(start -1.1049 -0.724916)
			(end 1.1049 -0.724916)
			(stroke
				(width 0.1)
				(type default)
			)
			(layer "B.Fab")
		)
		(fp_line
			(start 1.1049 -0.724916)
			(end 1.1049 0.724916)
			(stroke
				(width 0.1)
				(type default)
			)
			(layer "B.Fab")
		)
		(pad "1" smd rect
			(at 0.889 0 270)
			(size 1.016 1.27)
			(layers "B.Cu" "B.Mask" "B.Paste")
			(net "SW_P12V_AUX_PVDDCR_CPU0_P0_FLT")
		)
		(pad "2" smd rect
			(at -0.889 0 270)
			(size 1.016 1.27)
			(layers "B.Cu" "B.Mask" "B.Paste")
			(net "GND")
		)
	)
	(footprint ""
		(layer "B.Cu")
		(at 131.716526 -408.517344 90)
		(property "Reference" "C6736"
			(at 0 0 90)
			(layer "B.SilkS")
			(hide yes)
			(effects
				(font
					(size 1.27 1.27)
				)
				(justify mirror)
			)
		)
		(property "Value" ""
			(at 0 0 90)
			(layer "B.Fab")
			(effects
				(font
					(size 1.27 1.27)
				)
				(justify mirror)
			)
		)
		(duplicate_pad_numbers_are_jumpers no)
		(fp_line
			(start 0.299974 -0.150114)
			(end -0.299974 -0.150114)
			(stroke
				(width 0.1)
				(type default)
			)
			(layer "B.Fab")
		)
		(fp_line
			(start -0.299974 -0.150114)
			(end -0.299974 0.150114)
			(stroke
				(width 0.1)
				(type default)
			)
			(layer "B.Fab")
		)
		(fp_line
			(start 0.299974 0.150114)
			(end 0.299974 -0.150114)
			(stroke
				(width 0.1)
				(type default)
			)
			(layer "B.Fab")
		)
		(fp_line
			(start -0.299974 0.150114)
			(end 0.299974 0.150114)
			(stroke
				(width 0.1)
				(type default)
			)
			(layer "B.Fab")
		)
		(pad "1" smd rect
			(at 0.2667 0 270)
			(size 0.3048 0.381)
			(layers "B.Cu" "B.Mask" "B.Paste")
			(net "P5E_CPU1_P3_TX_BUF_C_DN<5>")
		)
		(pad "2" smd rect
			(at -0.2667 0 270)
			(size 0.3048 0.381)
			(layers "B.Cu" "B.Mask" "B.Paste")
			(net "P5E_CPU1_P3_TX_BUF_DN<5>")
		)
	)
	(footprint ""
		(layer "B.Cu")
		(at 125.468634 -268.855952 60)
		(property "Reference" "C2376"
			(at 0 0 60)
			(layer "B.SilkS")
			(hide yes)
			(effects
				(font
					(size 1.27 1.27)
				)
				(justify mirror)
			)
		)
		(property "Value" ""
			(at 0 0 60)
			(layer "B.Fab")
			(effects
				(font
					(size 1.27 1.27)
				)
				(justify mirror)
			)
		)
		(duplicate_pad_numbers_are_jumpers no)
		(fp_line
			(start -0.787516 -0.406438)
			(end -0.787425 0.40652)
			(stroke
				(width 0.1524)
				(type default)
			)
			(layer "B.SilkS")
		)
		(fp_line
			(start -0.787425 0.40652)
			(end 0.787516 0.406438)
			(stroke
				(width 0.1524)
				(type default)
			)
			(layer "B.SilkS")
		)
		(fp_line
			(start 0.787425 -0.40652)
			(end -0.787516 -0.406438)
			(stroke
				(width 0.1524)
				(type default)
			)
			(layer "B.SilkS")
		)
		(fp_line
			(start 0.787516 0.406438)
			(end 0.787425 -0.40652)
			(stroke
				(width 0.1524)
				(type default)
			)
			(layer "B.SilkS")
		)
		(fp_line
			(start -0.679568 -0.304811)
			(end -0.6795 0.304908)
			(stroke
				(width 0.1)
				(type default)
			)
			(layer "B.Fab")
		)
		(fp_line
			(start -0.120605 -0.304905)
			(end -0.679568 -0.304811)
			(stroke
				(width 0.1)
				(type default)
			)
			(layer "B.Fab")
		)
		(fp_line
			(start -0.120554 -0.279418)
			(end -0.120605 -0.304905)
			(stroke
				(width 0.1)
				(type default)
			)
			(layer "B.Fab")
		)
		(fp_line
			(start 0.120629 -0.30516)
			(end 0.120587 -0.279326)
			(stroke
				(width 0.1)
				(type default)
			)
			(layer "B.Fab")
		)
		(fp_line
			(start 0.120587 -0.279326)
			(end -0.120554 -0.279418)
			(stroke
				(width 0.1)
				(type default)
			)
			(layer "B.Fab")
		)
		(fp_line
			(start -0.6795 0.304908)
			(end -0.120316 0.304686)
			(stroke
				(width 0.1)
				(type default)
			)
			(layer "B.Fab")
		)
		(fp_line
			(start 0.679373 -0.305128)
			(end 0.120629 -0.30516)
			(stroke
				(width 0.1)
				(type default)
			)
			(layer "B.Fab")
		)
		(fp_line
			(start -0.12024 0.279419)
			(end 0.120554 0.279418)
			(stroke
				(width 0.1)
				(type default)
			)
			(layer "B.Fab")
		)
		(fp_line
			(start -0.120316 0.304686)
			(end -0.12024 0.279419)
			(stroke
				(width 0.1)
				(type default)
			)
			(layer "B.Fab")
		)
		(fp_line
			(start 0.120554 0.279418)
			(end 0.120605 0.304905)
			(stroke
				(width 0.1)
				(type default)
			)
			(layer "B.Fab")
		)
		(fp_line
			(start 0.120605 0.304905)
			(end 0.679568 0.304811)
			(stroke
				(width 0.1)
				(type default)
			)
			(layer "B.Fab")
		)
		(fp_line
			(start 0.679568 0.304811)
			(end 0.679373 -0.305128)
			(stroke
				(width 0.1)
				(type default)
			)
			(layer "B.Fab")
		)
		(pad "1" smd circle
			(at 0.40005 0 240)
			(size 0 0)
			(layers "B.Cu" "B.Mask" "B.Paste")
			(net "PVDDCR_CPU1_P1")
		)
		(pad "2" smd circle
			(at -0.40005 0 240)
			(size 0 0)
			(layers "B.Cu" "B.Mask" "B.Paste")
			(net "GND")
		)
	)
)
